# T6G (Grand Teton) — schematic netlist excerpt (pin names and nets, part order shuffled) for the footprints in the layout excerpt that follows; sources: Cadence DE-HDL packaged netlist, KiCad conversion of 04192023_DAF0TMB3IC0_F0TG_MB_C_brd_V02_OCP.brd

PR3790  Q_RES  7.15K 1% CHIP  pkg 0402LF  page 134 : A = P3V3_OCP_UV_1 ; B = P3V3_OCP_OV_1
R3553  Q_RES  33.2 1% CHIP  pkg 0402LF  page 235 : A = SMB_LM75_3_3V3AUX_SCL ; B = SMB_LM75_3_3V3AUX_SCL_R1

(kicad_pcb
	(version 20260206)
	(generator "pcbnew")
	(generator_version "10.0")
	(general
		(thickness 1.6)
		(legacy_teardrops no)
	)
	(paper "A4")
	(title_block
		(title "04192023_DAF0TMB3IC0_F0TG_MB_C_brd_V02_OCP.brd")
		(comment 1 "Grand Teton / footprints 1506-1507 of 8354")
	)
	(layers
		(0 "F.Cu" signal "TOP")
		(4 "In1.Cu" signal "GND")
		(6 "In2.Cu" signal "IN1")
		(8 "In3.Cu" signal "GND1")
		(10 "In4.Cu" signal "IN2")
		(12 "In5.Cu" signal "GND2")
		(14 "In6.Cu" signal "IN3")
		(16 "In7.Cu" signal "GND3")
		(18 "In8.Cu" signal "VCC")
		(20 "In9.Cu" signal "VCC1")
		(22 "In10.Cu" signal "GND4")
		(24 "In11.Cu" signal "IN4")
		(26 "In12.Cu" signal "GND5")
		(28 "In13.Cu" signal "IN5")
		(30 "In14.Cu" signal "GND6")
		(32 "In15.Cu" signal "IN6")
		(34 "In16.Cu" signal "GND7")
		(2 "B.Cu" signal "BOTTOM")
		(9 "F.Adhes" user "F.Adhesive")
		(11 "B.Adhes" user "B.Adhesive")
		(13 "F.Paste" user "Package Geometry/Pastemask Top")
		(15 "B.Paste" user "Package Geometry/Pastemask Bottom")
		(5 "F.SilkS" user "Ref Des/Silkscreen Top")
		(7 "B.SilkS" user "Ref Des/Silkscreen Bottom")
		(1 "F.Mask" user "Board Geometry/Soldermask Top")
		(3 "B.Mask" user "Board Geometry/Soldermask Bottom")
		(17 "Dwgs.User" user "User.Drawings")
		(19 "Cmts.User" user "User.Comments")
		(21 "Eco1.User" user "User.Eco1")
		(23 "Eco2.User" user "User.Eco2")
		(25 "Edge.Cuts" user "Board Geometry/Outline")
		(27 "Margin" user)
		(31 "F.CrtYd" user "Package Geometry/Place Bound Top")
		(29 "B.CrtYd" user "Package Geometry/Place Bound Bottom")
		(35 "F.Fab" user "Ref Des/Assembly Top")
		(33 "B.Fab" user "Ref Des/Assembly Bottom")
	)
	(footprint ""
		(layer "F.Cu")
		(at 428.912782 -107.872276 180)
		(property "Reference" "PR3790"
			(at 0 0 180)
			(layer "F.SilkS")
			(hide yes)
			(effects
				(font
					(size 1.27 1.27)
				)
			)
		)
		(property "Value" ""
			(at 0 0 180)
			(layer "F.Fab")
			(effects
				(font
					(size 1.27 1.27)
				)
			)
		)
		(duplicate_pad_numbers_are_jumpers no)
		(fp_line
			(start 0.7874 0.4064)
			(end -0.7874 0.4064)
			(stroke
				(width 0.1524)
				(type default)
			)
			(layer "F.SilkS")
		)
		(fp_line
			(start 0.7874 -0.4064)
			(end 0.7874 0.4064)
			(stroke
				(width 0.1524)
				(type default)
			)
			(layer "F.SilkS")
		)
		(fp_line
			(start -0.7874 0.4064)
			(end -0.7874 -0.4064)
			(stroke
				(width 0.1524)
				(type default)
			)
			(layer "F.SilkS")
		)
		(fp_line
			(start -0.7874 -0.4064)
			(end 0.7874 -0.4064)
			(stroke
				(width 0.1524)
				(type default)
			)
			(layer "F.SilkS")
		)
		(fp_line
			(start 0.67945 0.3048)
			(end 0.120396 0.3048)
			(stroke
				(width 0.1)
				(type default)
			)
			(layer "F.Fab")
		)
		(fp_line
			(start 0.67945 -0.3048)
			(end 0.67945 0.3048)
			(stroke
				(width 0.1)
				(type default)
			)
			(layer "F.Fab")
		)
		(fp_line
			(start 0.12065 -0.2794)
			(end 0.12065 -0.3048)
			(stroke
				(width 0.1)
				(type default)
			)
			(layer "F.Fab")
		)
		(fp_line
			(start 0.12065 -0.3048)
			(end 0.67945 -0.3048)
			(stroke
				(width 0.1)
				(type default)
			)
			(layer "F.Fab")
		)
		(fp_line
			(start 0.120396 0.3048)
			(end 0.120396 0.2794)
			(stroke
				(width 0.1)
				(type default)
			)
			(layer "F.Fab")
		)
		(fp_line
			(start 0.120396 0.2794)
			(end -0.12065 0.2794)
			(stroke
				(width 0.1)
				(type default)
			)
			(layer "F.Fab")
		)
		(fp_line
			(start -0.12065 0.3048)
			(end -0.67945 0.3048)
			(stroke
				(width 0.1)
				(type default)
			)
			(layer "F.Fab")
		)
		(fp_line
			(start -0.12065 0.2794)
			(end -0.12065 0.3048)
			(stroke
				(width 0.1)
				(type default)
			)
			(layer "F.Fab")
		)
		(fp_line
			(start -0.12065 -0.2794)
			(end 0.12065 -0.2794)
			(stroke
				(width 0.1)
				(type default)
			)
			(layer "F.Fab")
		)
		(fp_line
			(start -0.12065 -0.305054)
			(end -0.12065 -0.2794)
			(stroke
				(width 0.1)
				(type default)
			)
			(layer "F.Fab")
		)
		(fp_line
			(start -0.67945 0.3048)
			(end -0.67945 -0.305054)
			(stroke
				(width 0.1)
				(type default)
			)
			(layer "F.Fab")
		)
		(fp_line
			(start -0.67945 -0.305054)
			(end -0.12065 -0.305054)
			(stroke
				(width 0.1)
				(type default)
			)
			(layer "F.Fab")
		)
		(pad "1" smd circle
			(at -0.40005 0 180)
			(size 0 0)
			(layers "F.Cu" "F.Mask" "F.Paste")
			(net "P3V3_OCP_UV_1")
		)
		(pad "2" smd circle
			(at 0.40005 0 180)
			(size 0 0)
			(layers "F.Cu" "F.Mask" "F.Paste")
			(net "P3V3_OCP_OV_1")
		)
	)
	(footprint ""
		(layer "F.Cu")
		(at 106.892598 -16.98371)
		(property "Reference" "R3553"
			(at 0 0 0)
			(layer "F.SilkS")
			(hide yes)
			(effects
				(font
					(size 1.27 1.27)
				)
			)
		)
		(property "Value" ""
			(at 0 0 0)
			(layer "F.Fab")
			(effects
				(font
					(size 1.27 1.27)
				)
			)
		)
		(duplicate_pad_numbers_are_jumpers no)
		(fp_line
			(start -0.7874 -0.4064)
			(end 0.7874 -0.4064)
			(stroke
				(width 0.1524)
				(type default)
			)
			(layer "F.SilkS")
		)
		(fp_line
			(start -0.7874 0.4064)
			(end -0.7874 -0.4064)
			(stroke
				(width 0.1524)
				(type default)
			)
			(layer "F.SilkS")
		)
		(fp_line
			(start 0.7874 -0.4064)
			(end 0.7874 0.4064)
			(stroke
				(width 0.1524)
				(type default)
			)
			(layer "F.SilkS")
		)
		(fp_line
			(start 0.7874 0.4064)
			(end -0.7874 0.4064)
			(stroke
				(width 0.1524)
				(type default)
			)
			(layer "F.SilkS")
		)
		(fp_line
			(start -0.67945 -0.305054)
			(end -0.12065 -0.305054)
			(stroke
				(width 0.1)
				(type default)
			)
			(layer "F.Fab")
		)
		(fp_line
			(start -0.67945 0.3048)
			(end -0.67945 -0.305054)
			(stroke
				(width 0.1)
				(type default)
			)
			(layer "F.Fab")
		)
		(fp_line
			(start -0.12065 -0.305054)
			(end -0.12065 -0.2794)
			(stroke
				(width 0.1)
				(type default)
			)
			(layer "F.Fab")
		)
		(fp_line
			(start -0.12065 -0.2794)
			(end 0.12065 -0.2794)
			(stroke
				(width 0.1)
				(type default)
			)
			(layer "F.Fab")
		)
		(fp_line
			(start -0.12065 0.2794)
			(end -0.12065 0.3048)
			(stroke
				(width 0.1)
				(type default)
			)
			(layer "F.Fab")
		)
		(fp_line
			(start -0.12065 0.3048)
			(end -0.67945 0.3048)
			(stroke
				(width 0.1)
				(type default)
			)
			(layer "F.Fab")
		)
		(fp_line
			(start 0.120396 0.2794)
			(end -0.12065 0.2794)
			(stroke
				(width 0.1)
				(type default)
			)
			(layer "F.Fab")
		)
		(fp_line
			(start 0.120396 0.3048)
			(end 0.120396 0.2794)
			(stroke
				(width 0.1)
				(type default)
			)
			(layer "F.Fab")
		)
		(fp_line
			(start 0.12065 -0.3048)
			(end 0.67945 -0.3048)
			(stroke
				(width 0.1)
				(type default)
			)
			(layer "F.Fab")
		)
		(fp_line
			(start 0.12065 -0.2794)
			(end 0.12065 -0.3048)
			(stroke
				(width 0.1)
				(type default)
			)
			(layer "F.Fab")
		)
		(fp_line
			(start 0.67945 -0.3048)
			(end 0.67945 0.3048)
			(stroke
				(width 0.1)
				(type default)
			)
			(layer "F.Fab")
		)
		(fp_line
			(start 0.67945 0.3048)
			(end 0.120396 0.3048)
			(stroke
				(width 0.1)
				(type default)
			)
			(layer "F.Fab")
		)
		(pad "1" smd circle
			(at -0.40005 0)
			(size 0 0)
			(layers "F.Cu" "F.Mask" "F.Paste")
			(net "SMB_LM75_3_3V3AUX_SCL")
		)
		(pad "2" smd circle
			(at 0.40005 0)
			(size 0 0)
			(layers "F.Cu" "F.Mask" "F.Paste")
			(net "SMB_LM75_3_3V3AUX_SCL_R1")
		)
	)
)
